G04 ================== begin FILE IDENTIFICATION RECORD ==================*
G04 Layout Name:  12432-1.brd*
G04 Film Name:    DIF_REF_L3*
G04 File Format:  Gerber RS274X*
G04 File Origin:  Cadence Allegro 16.2-S037*
G04 Origin Date:  Wed Oct 17 11:00:20 2012*
G04 *
G04 Layer:  BOARD GEOMETRY/OUTLINE*
G04 Layer:  BOARD GEOMETRY/DIF_REF_L3*
G04 Layer:  BOARD GEOMETRY/PANEL_OUTLINE*
G04 *
G04 Offset:    (0.00 0.00)*
G04 Mirror:    No*
G04 Mode:      Positive*
G04 Rotation:  0*
G04 FullContactRelief:  No*
G04 UndefLineWidth:     6.00*
G04 ================== end FILE IDENTIFICATION RECORD ====================*
%FSLAX35Y35*MOIN*%
%IR0*IPPOS*OFA0.00000B0.00000*MIA0B0*SFA1.00000B1.00000*%
%ADD10C,.01*%
%ADD11C,.004*%
%ADD12C,.006*%
G75*
%LPD*%
G75*
G54D10*
G01X-78740Y15000D02*
G03X-63740Y0I15000J0D01*
G01X-78740Y15000D02*
Y319646D01*
G01X-63740Y334646D02*
G03X-78740Y319646I0J-15000D01*
G01Y908315D02*
G03X-63740Y893315I15000J0D01*
G01X-78740Y908315D02*
Y1304286D01*
G01X-63740Y1319286D02*
G03X-78740Y1304286I0J-15000D01*
G01Y1892953D02*
G03X-63740Y1877953I15000J0D01*
G01X-78740Y1892953D02*
Y1977126D01*
G01X-63740Y1992126D02*
G03X-78740Y1977126I0J-15000D01*
G01X-7874Y0D02*
X-63740D01*
G01X-7874Y334646D02*
X-63740D01*
G01X-7874Y893315D02*
X-63740D01*
G01X-7874Y1319286D02*
X-63740D01*
G01X-7874Y1877953D02*
X-63740D01*
G01X-7874Y1992126D02*
X-63740D01*
G01X-7874Y17253D02*
Y0D01*
G01X0Y17214D02*
G03X-7874I-3937J0D01*
G01Y41772D02*
Y167110D01*
G01Y41772D02*
G03X0I3937J0D01*
G01Y167110D02*
G03X-7874I-3937J0D01*
G01Y191667D02*
Y308383D01*
G01Y191667D02*
G03X0I3937J0D01*
G01Y308383D02*
G03X-7874I-3937J0D01*
G01Y331986D02*
Y334646D01*
G01Y332003D02*
G03X0I3937J0D01*
G01X-7874Y905988D02*
Y893315D01*
G01X0Y905988D02*
G03X-7874I-3937J0D01*
G01Y1106301D02*
Y933234D01*
G01D02*
G03X0I3937J0D01*
G01Y1106301D02*
G03X-7874I-3937J0D01*
G01Y1280567D02*
Y1129921D01*
G01D02*
G03X0I3937J0D01*
G01Y1280567D02*
G03X-7874I-3937J0D01*
G01Y1309889D02*
Y1319286D01*
G01Y1309889D02*
G03X0I3937J0D01*
G01X-7874Y1889223D02*
Y1877953D01*
G01X0Y1889223D02*
G03X-7874I-3937J0D01*
G01X0D02*
G03X-7874I-3937J0D01*
G01Y1912843D02*
Y1962927D01*
G01Y1912843D02*
G03X0I3937J0D01*
G01Y1962927D02*
G03X-7874I-3937J0D01*
G01X0D02*
G03X-7874I-3937J0D01*
G01Y1986547D02*
Y1992126D01*
G01Y1986547D02*
G03X0I3937J0D01*
G01X3937Y0D02*
X1029528D01*
G01X0Y3937D02*
G03X3937Y0I3937J0D01*
G01X0Y409646D02*
Y3937D01*
G01X3937Y413583D02*
X0Y409646D01*
G01X19882Y413583D02*
X3937D01*
G01Y421063D02*
X19882D01*
G01X0Y425000D02*
X3937Y421063D01*
G01X0Y819094D02*
Y425000D01*
G01X3937Y823031D02*
X0Y819094D01*
G01X19882Y823031D02*
X3937D01*
G01Y830512D02*
X19882D01*
G01X0Y834449D02*
X3937Y830512D01*
G01X0Y1393898D02*
Y834449D01*
G01X3937Y1397835D02*
X0Y1393898D01*
G01X19882Y1397835D02*
X3937D01*
G01Y1405315D02*
X19882D01*
G01X0Y1409252D02*
X3937Y1405315D01*
G01X0Y1803346D02*
Y1409252D01*
G01X3937Y1807283D02*
X0Y1803346D01*
G01X19882Y1807283D02*
X3937D01*
G01Y1814764D02*
X19882D01*
G01X0Y1818701D02*
X3937Y1814764D01*
G01X0Y1988189D02*
Y1818701D01*
G01X3937Y1992126D02*
G03X0Y1988189I0J-3937D01*
G01X1029528Y1992126D02*
X3937D01*
G01X19882Y413583D02*
G03Y421063I0J3740D01*
G01Y823031D02*
G03Y830512I0J3741D01*
G01Y1397835D02*
G03Y1405315I0J3740D01*
G01Y1807283D02*
G03Y1814764I0J3740D01*
G01X989744Y1616083D02*
X1015354D01*
G01X989744D02*
G03Y1611870I0J-2107D01*
G01X1015354D02*
X989744D01*
G01X1033465Y3937D02*
Y1424882D01*
G01X1029528Y0D02*
G03X1033465Y3937I0J3937D01*
G01X1041338Y24677D02*
G03X1033464I-3937J0D01*
G01X1041338D02*
G03X1033464I-3937J0D01*
G01Y48297D02*
G03X1041338I3937J0D01*
G01Y217343D02*
G03X1033464I-3937J0D01*
G01X1041338D02*
G03X1033464I-3937J0D01*
G01Y240964D02*
G03X1041338I3937J0D01*
G01X1033464D02*
G03X1041338I3937J0D01*
G01Y445039D02*
G03X1033464I-3937J0D01*
G01X1041338D02*
G03X1033464I-3937J0D01*
G01Y468659D02*
G03X1041338I3937J0D01*
G01X1033464D02*
G03X1041338I3937J0D01*
G01Y697473D02*
G03X1033464I-3937J0D01*
G01X1041338D02*
G03X1033464I-3937J0D01*
G01Y721093D02*
G03X1041338I3937J0D01*
G01X1033464D02*
G03X1041338I3937J0D01*
G01Y996852D02*
G03X1033464I-3937J0D01*
G01X1041338D02*
G03X1033464I-3937J0D01*
G01Y1020472D02*
G03X1041338I3937J0D01*
G01X1033464D02*
G03X1041338I3937J0D01*
G01Y1344060D02*
G03X1033464I-3937J0D01*
G01X1041338D02*
G03X1033464I-3937J0D01*
G01Y1367680D02*
G03X1041338I3937J0D01*
G01X1033464D02*
G03X1041338I3937J0D01*
G01X1033465Y1424882D02*
X1029528Y1428819D01*
G01X1019291Y1433740D02*
Y1607933D01*
G01Y1433740D02*
G03X1024213Y1428819I4921J0D01*
G01X1029528D02*
X1024213D01*
G01X1015354Y1616083D02*
X1019291Y1620020D01*
G01Y1607933D02*
X1015354Y1611870D01*
G01X1019291Y1620020D02*
Y1676496D01*
G01X1029528Y1681417D02*
X1033465Y1685354D01*
G01X1024213Y1681417D02*
G03X1019291Y1676496I-1J-4921D01*
G01X1033465Y1685354D02*
Y1988189D01*
G01X1024213Y1681417D02*
X1029528D01*
G01X1041338Y1739719D02*
G03X1033464I-3937J0D01*
G01X1041338D02*
G03X1033464I-3937J0D01*
G01Y1763339D02*
G03X1041338I3937J0D01*
G01X1033464D02*
G03X1041338I3937J0D01*
G01Y1959242D02*
G03X1033464I-3937J0D01*
G01X1041338D02*
G03X1033464I-3937J0D01*
G01X1033465Y1988189D02*
G03X1029528Y1992126I-3937J0D01*
G01X1033464Y1982862D02*
G03X1041338I3937J0D01*
G01Y24677D02*
Y0D01*
G01D02*
X1097205D01*
G01X1041338Y217343D02*
Y48297D01*
G01Y445039D02*
Y240964D01*
G01Y697473D02*
Y468601D01*
G01Y996852D02*
Y721093D01*
G01Y1344060D02*
Y1020472D01*
G01Y1367680D02*
Y1393701D01*
G01D02*
X1097205D01*
G01X1041338Y1733129D02*
Y1716536D01*
G01X1065043D02*
X1041338D01*
G01Y1739719D02*
Y1731536D01*
G01Y1959242D02*
Y1763310D01*
G01Y1992126D02*
X1097205D01*
G01X1041338Y1982862D02*
Y1992126D01*
G01X1056338Y1716536D02*
X1097205D01*
G01Y0D02*
G03X1112205Y15000I0J15000D01*
G01Y1378701D02*
G03X1097205Y1393701I-15000J0D01*
G01Y1716536D02*
G03X1112205Y1731536I0J15000D01*
G01Y1977126D02*
G03X1097205Y1992126I-15000J0D01*
G01X1112205Y648419D02*
Y15000D01*
G01Y656293D02*
G03Y648419I0J-3937D01*
G01Y1378701D02*
Y656293D01*
G01Y1977126D02*
Y1731536D01*
G54D11*
G01X64580Y465083D02*
X30154D01*
G01D02*
G03X28884Y464557I0J-1796D01*
G01D02*
G02X26914I-985J985D01*
G01D02*
G02X26499Y465559I1002J1002D01*
G01D02*
Y466250D01*
G01X64582Y463883D02*
X30153D01*
G01D02*
G03X29733Y463708I2J-596D01*
G01D02*
G02X27841Y462948I-1835J1833D01*
G01D02*
X27265Y462961D01*
G01D02*
G03X26486Y462648I-23J-1068D01*
G01X76352Y480831D02*
X31039D01*
G01D02*
G03X28927Y479956I0J-2987D01*
G01D02*
G02X28573Y479809I-354J353D01*
G01D02*
X27807D01*
G01D02*
G02X27181Y480068I0J886D01*
G01D02*
X27062Y480187D01*
G01D02*
G02X26921Y480528I342J341D01*
G01D02*
Y480632D01*
G01D02*
G03X26884Y480817I-483J0D01*
G01D02*
X26720Y481213D01*
G01D02*
G03X26686Y481386I-452J1D01*
G01D02*
X26515Y481798D01*
G01X76352Y479631D02*
X31040D01*
G01D02*
G03X29777Y479107I1J-1786D01*
G01D02*
G02X29561Y478924I-1203J1201D01*
G01D02*
G02X27936Y478404I-1625J2278D01*
G01D02*
X26299D01*
G01X26599Y529302D02*
G03X29561Y528075I2962J2962D01*
G01D02*
X54499D01*
G01X26599Y525648D02*
Y525867D01*
G01D02*
G02X28158Y527061I1237J0D01*
G01D02*
G03X29562Y526875I1404J5202D01*
G01D02*
X39059D01*
G01D02*
G02X39346Y526588I0J-287D01*
G01D02*
Y526587D01*
G01D02*
G03X39633Y526300I287J0D01*
G01D02*
X41459D01*
G01X54499Y528075D02*
Y528074D01*
G01D02*
G02X58208Y526540I3J-5244D01*
G01D02*
X59348Y525399D01*
G01D02*
G03X73469Y519550I14121J14121D01*
G01X41459Y526300D02*
G03X41746Y526587I0J287D01*
G01D02*
Y526588D01*
G01D02*
G02X42033Y526875I287J0D01*
G01D02*
X43859D01*
G01D02*
G02X44146Y526588I0J-287D01*
G01D02*
Y526587D01*
G01D02*
G03X44433Y526300I287J0D01*
G01D02*
X46259D01*
G01D02*
G03X46546Y526587I0J287D01*
G01D02*
Y526588D01*
G01D02*
G02X46833Y526875I287J0D01*
G01D02*
X48659D01*
G01D02*
G02X48946Y526588I0J-287D01*
G01D02*
Y526587D01*
G01D02*
G03X49233Y526300I287J0D01*
G01D02*
X51059D01*
G01D02*
G03X51346Y526587I0J287D01*
G01D02*
Y526588D01*
G01D02*
G02X51633Y526875I287J0D01*
G01D02*
X54499D01*
G01D02*
G02X57359Y525691I1J-4044D01*
G01D02*
X58499Y524550D01*
G01D02*
G03X73470Y518350I14969J14970D01*
G01X145469Y543327D02*
X69095Y466953D01*
G01D02*
G02X64580Y465083I-4515J4515D01*
G01X146318Y542478D02*
X69944Y466104D01*
G01D02*
G02X64582Y463883I-5362J5362D01*
G01X114269Y517478D02*
X78520Y481729D01*
G01D02*
G02X76352Y480831I-2168J2168D01*
G01X113708Y515218D02*
X79369Y480880D01*
G01D02*
G02X76352Y479631I-3016J3017D01*
G01X73469Y519550D02*
X95117D01*
G01X73470Y518350D02*
X86373D01*
G01X97049Y518749D02*
G02X98000Y516456I-2294J-2295D01*
G01D02*
Y515573D01*
G01D02*
G03X98900Y513400I3073J0D01*
G01X96201Y517901D02*
G02X96800Y516455I-1446J-1446D01*
G01D02*
Y515900D01*
G01D02*
G02X95951Y513852I-2897J1D01*
G01D02*
X95500Y513400D01*
G01X95117Y519550D02*
G02X97049Y518750I0J-2733D01*
G01D02*
Y518749D01*
G01X86373Y518350D02*
G02X86673Y518050I0J-300D01*
G01D02*
G03X86973Y517750I300J0D01*
G01D02*
X88773D01*
G01D02*
G03X89073Y518050I0J300D01*
G01D02*
G02X89373Y518350I300J0D01*
G01D02*
X95117D01*
G01D02*
G02X96201Y517901I0J-1533D01*
G01X114920Y518128D02*
X114270Y517478D01*
G01D02*
X114269D01*
G01X117051Y520376D02*
G02X115769Y517279I-4379J-1D01*
G01D02*
X113708Y515218D01*
G01X115851Y807000D02*
Y520376D01*
G01D02*
G02X114920Y518128I-3179J0D01*
G01X117051Y807000D02*
Y520376D01*
G01X122099Y819233D02*
G02X118752Y811148I-11433J-2D01*
G01D02*
X118751Y811149D01*
G01D02*
X116733Y809131D01*
G01D02*
G03X115851Y807000I2131J-2130D01*
G01X123300Y819233D02*
G02X119600Y810300I-12633J0D01*
G01D02*
X117582Y808282D01*
G01D02*
G03X117051Y807000I1282J-1282D01*
G01X122100Y1036164D02*
Y819232D01*
G01D02*
X122099Y819233D01*
G01X123300Y1036163D02*
Y819233D01*
G01X128099Y1045450D02*
X124424Y1041775D01*
G01D02*
G03X122100Y1036164I5612J-5611D01*
G01X125273Y1040926D02*
G03X123300Y1036163I4763J-4763D01*
G01X123999Y1050650D02*
X124811Y1051463D01*
G01X123999Y1054050D02*
G03X126001Y1053075I2414J2414D01*
G01X146639Y546150D02*
G02X145469Y543327I-3993J1D01*
G01X131400Y644600D02*
G02X130200Y647497I2897J2897D01*
G01D02*
Y648800D01*
G01D02*
G03X129210Y651190I-3380J0D01*
G01D02*
X127800Y652600D01*
G01D02*
G02X127100Y654290I1690J1690D01*
G01D02*
Y657700D01*
G01D02*
G02X127948Y659748I2897J0D01*
G01D02*
X128400Y660200D01*
G01D02*
G02X129849Y660800I1449J-1449D01*
G01D02*
X136627D01*
G01D02*
G02X138800Y659900I0J-3073D01*
G01D02*
X146950Y651750D01*
G01X127999Y645550D02*
G03X129000Y647967I-2417J2417D01*
G01D02*
Y648799D01*
G01D02*
G03X128361Y650341I-2180J0D01*
G01D02*
X126951Y651751D01*
G01D02*
G02X125900Y654290I2539J2538D01*
G01D02*
Y657699D01*
G01D02*
G02X127099Y660597I4097J2D01*
G01D02*
X127551Y661049D01*
G01D02*
X127552Y661048D01*
G01D02*
G02X129850Y662000I2298J-2297D01*
G01D02*
X136626D01*
G01D02*
G02X139648Y660748I0J-4273D01*
G01D02*
X139649Y660749D01*
G01D02*
X147799Y652599D01*
G01X128799Y1047140D02*
G02X128099Y1045450I-2390J0D01*
G01X129999Y1047141D02*
G02X128947Y1044602I-3590J0D01*
G01D02*
X128948Y1044601D01*
G01D02*
X125273Y1040926D01*
G01X124811Y1051463D02*
G02X125745Y1051850I934J-934D01*
G01D02*
X126999D01*
G01D02*
Y1051849D01*
G01D02*
G02X128194Y1051355I1J-1690D01*
G01D02*
G02X128799Y1049894I-1461J-1461D01*
G01D02*
Y1047140D01*
G01X126001Y1053075D02*
X126002D01*
G01D02*
G03X126413Y1053050I412J3389D01*
G01D02*
X127000D01*
G01D02*
G02X129042Y1052204I-1J-2890D01*
G01D02*
Y1052203D01*
G01D02*
G02X129999Y1049893I-2309J-2310D01*
G01D02*
Y1047141D01*
G01X146639Y582017D02*
Y559629D01*
G01D02*
G02X146370Y559360I-269J0D01*
G01D02*
X146369D01*
G01D02*
G03X146100Y559091I0J-269D01*
G01D02*
Y557229D01*
G01D02*
G03X146369Y556960I269J0D01*
G01D02*
X146370D01*
G01D02*
G02X146639Y556691I0J-269D01*
G01D02*
Y554829D01*
G01D02*
G02X146370Y554560I-269J0D01*
G01D02*
X146369D01*
G01D02*
G03X146100Y554291I0J-269D01*
G01D02*
Y552429D01*
G01D02*
G03X146369Y552160I269J0D01*
G01D02*
X146370D01*
G01D02*
G02X146639Y551891I0J-269D01*
G01D02*
Y546150D01*
G01X147839Y597550D02*
Y546149D01*
G01D02*
G02X146318Y542478I-5193J1D01*
G01X156650Y609399D02*
X147938Y600686D01*
G01D02*
G03X146640Y597550I3136J-3135D01*
G01D02*
X146639D01*
G01D02*
Y594555D01*
G01D02*
G02X146370Y594286I-269J0D01*
G01D02*
X146369D01*
G01D02*
G03X146100Y594017I0J-269D01*
G01D02*
Y592155D01*
G01D02*
G03X146369Y591886I269J0D01*
G01D02*
X146370D01*
G01D02*
G02X146639Y591617I0J-269D01*
G01D02*
Y589755D01*
G01D02*
G02X146370Y589486I-269J0D01*
G01D02*
X146369D01*
G01D02*
G03X146100Y589217I0J-269D01*
G01D02*
Y587355D01*
G01D02*
G03X146369Y587086I269J0D01*
G01D02*
X146370D01*
G01D02*
G02X146639Y586817I0J-269D01*
G01D02*
Y584955D01*
G01D02*
G02X146370Y584686I-269J0D01*
G01D02*
X146369D01*
G01D02*
G03X146100Y584417I0J-269D01*
G01D02*
Y582555D01*
G01D02*
G03X146369Y582286I269J0D01*
G01D02*
X146370D01*
G01D02*
G02X146639Y582017I0J-269D01*
G01X157499Y608550D02*
X148787Y599837D01*
G01D02*
G03X147839Y597550I2287J-2288D01*
G01X157799Y636036D02*
Y612172D01*
G01D02*
G02X156651Y609398I-3921J-2D01*
G01D02*
X156650Y609399D01*
G01X158999Y636037D02*
Y612171D01*
G01D02*
G02X157499Y608550I-5121J0D01*
G01X148271Y648561D02*
Y642378D01*
G01D02*
G03X151199Y639450I2928J0D01*
G01D02*
X154385D01*
G01D02*
G02X156799Y638450I0J-3414D01*
G01D02*
G02X157799Y636036I-2414J-2414D01*
G01X149471Y648562D02*
Y642378D01*
G01D02*
G03X151199Y640650I1728J0D01*
G01D02*
X154386D01*
G01D02*
G02X157648Y639299I0J-4614D01*
G01D02*
G02X158999Y636037I-3263J-3262D01*
G01X146950Y651750D02*
G02X148271Y648561I-3189J-3189D01*
G01X147799Y652599D02*
X147798Y652598D01*
G01D02*
G02X149471Y648562I-4037J-4038D01*
G54D12*
G01X1019291Y1620020D02*
Y1676496D01*
G02X1024213Y1681417I4921J0D01*
G01X1029528D01*
X1033465Y1685354D01*
Y1988189D01*
G03X1029528Y1992126I-3937J0D01*
G01X3937D01*
G03X0Y1988189I0J-3937D01*
G01Y1818701D01*
X3937Y1814764D01*
X19882D01*
G02Y1807283I0J-3740D01*
G01X3937D01*
X0Y1803346D01*
Y1409252D01*
X3937Y1405315D01*
X19882D01*
G02Y1397835I0J-3740D01*
G01X3937D01*
X0Y1393898D01*
Y834449D01*
X3937Y830512D01*
X19882D01*
G02Y823031I0J-3740D01*
G01X3937D01*
X0Y819094D01*
Y425000D01*
X3937Y421063D01*
X19882D01*
G02Y413583I0J-3740D01*
G01X3937D01*
X0Y409646D01*
Y3937D01*
G03X3937Y0I3937J0D01*
G01X1029528D01*
G03X1033465Y3937I0J3937D01*
G01Y1424882D01*
X1029528Y1428819D01*
X1024213D01*
G02X1019291Y1433740I-1J4921D01*
G01Y1607933D01*
X1015354Y1611870D01*
X989744D01*
G02Y1616083I0J2107D01*
G01X1015354D01*
X1019291Y1620020D01*
G01X24705Y1903150D02*
G02X10728I-6989J0D01*
G02X24705I6988J0D01*
G01X30639Y-130979D02*
Y-142979D01*
G01X28339Y-130979D02*
X32939D01*
G01X34939Y-142979D02*
Y-130979D01*
G01Y-136779D02*
X35439Y-135779D01*
X35939Y-135179D01*
X36739Y-134979D01*
X37339Y-135179D01*
X38039Y-135979D01*
X38339Y-137179D01*
Y-142979D01*
G01X42639Y-134979D02*
Y-142979D01*
G01Y-131779D02*
X42439Y-131579D01*
Y-131179D01*
X42639Y-130979D01*
X42839Y-131179D01*
Y-131579D01*
X42639Y-131779D01*
G01X47139Y-141579D02*
X47639Y-142379D01*
X48339Y-142979D01*
X48939D01*
X49539Y-142579D01*
X49939Y-141979D01*
X50139Y-141179D01*
X50039Y-139979D01*
X49639Y-139379D01*
X47839Y-138179D01*
X47439Y-136779D01*
X47639Y-135779D01*
X48039Y-135179D01*
X48639Y-134979D01*
X49239Y-135179D01*
X49839Y-135779D01*
G01X59239Y-145979D02*
X59939Y-146779D01*
X60739Y-146979D01*
X61439Y-146779D01*
X62039Y-145779D01*
X62439Y-144379D01*
Y-134979D01*
G01Y-136579D02*
X62039Y-135779D01*
X61439Y-135179D01*
X60739Y-134979D01*
X59939Y-135379D01*
X59439Y-136179D01*
X59039Y-137579D01*
X58839Y-138979D01*
X58939Y-140179D01*
X59339Y-141579D01*
X59939Y-142579D01*
X60739Y-142979D01*
X61339Y-142779D01*
X62039Y-141979D01*
X62439Y-141179D01*
G01X65139Y-137579D02*
X68339D01*
X68039Y-136179D01*
X67539Y-135379D01*
X66839Y-134979D01*
X66139Y-135179D01*
X65539Y-135779D01*
X65139Y-137179D01*
X64939Y-138379D01*
Y-139579D01*
X65139Y-140779D01*
X65639Y-141979D01*
X66239Y-142779D01*
X66939Y-142979D01*
X67639Y-142579D01*
X68339Y-141379D01*
G01X71239Y-142979D02*
Y-134979D01*
G01Y-136579D02*
X71739Y-135779D01*
X72239Y-135179D01*
X72939Y-134979D01*
X73439Y-135179D01*
X74039Y-135779D01*
G01X76839Y-142979D02*
Y-130979D01*
G01Y-136979D02*
X77339Y-135779D01*
X77939Y-135179D01*
X78539Y-134979D01*
X79439Y-135379D01*
X80039Y-136179D01*
X80439Y-137579D01*
Y-139179D01*
X80239Y-140779D01*
X79839Y-141979D01*
X79139Y-142779D01*
X78539Y-142979D01*
X77939Y-142779D01*
X77339Y-142179D01*
X76839Y-141179D01*
G01X83139Y-137579D02*
X86339D01*
X86039Y-136179D01*
X85539Y-135379D01*
X84839Y-134979D01*
X84139Y-135179D01*
X83539Y-135779D01*
X83139Y-137179D01*
X82939Y-138379D01*
Y-139579D01*
X83139Y-140779D01*
X83639Y-141979D01*
X84239Y-142779D01*
X84939Y-142979D01*
X85639Y-142579D01*
X86339Y-141379D01*
G01X89239Y-142979D02*
Y-134979D01*
G01Y-136579D02*
X89739Y-135779D01*
X90239Y-135179D01*
X90939Y-134979D01*
X91439Y-135179D01*
X92039Y-135779D01*
G01X102639Y-134979D02*
Y-142979D01*
G01Y-131779D02*
X102439Y-131579D01*
Y-131179D01*
X102639Y-130979D01*
X102839Y-131179D01*
Y-131579D01*
X102639Y-131779D01*
G01X107139Y-141579D02*
X107639Y-142379D01*
X108339Y-142979D01*
X108939D01*
X109539Y-142579D01*
X109939Y-141979D01*
X110139Y-141179D01*
X110039Y-139979D01*
X109639Y-139379D01*
X107839Y-138179D01*
X107439Y-136779D01*
X107639Y-135779D01*
X108039Y-135179D01*
X108639Y-134979D01*
X109239Y-135179D01*
X109839Y-135779D01*
G01X119039Y-145979D02*
X119739Y-146779D01*
X120339Y-146979D01*
X121139Y-146579D01*
X121739Y-145579D01*
X122039Y-143779D01*
Y-134979D01*
G01Y-131779D02*
X121839Y-131579D01*
Y-131179D01*
X122039Y-130979D01*
X122239Y-131179D01*
Y-131579D01*
X122039Y-131779D01*
G01X124939Y-134979D02*
Y-140579D01*
X125339Y-141979D01*
X125939Y-142779D01*
X126639Y-142979D01*
X127339Y-142779D01*
X127939Y-141979D01*
X128339Y-140579D01*
G01Y-142979D02*
Y-134979D01*
G01X131139Y-141579D02*
X131639Y-142379D01*
X132339Y-142979D01*
X132939D01*
X133539Y-142579D01*
X133939Y-141979D01*
X134139Y-141179D01*
X134039Y-139979D01*
X133639Y-139379D01*
X131839Y-138179D01*
X131439Y-136779D01*
X131639Y-135779D01*
X132039Y-135179D01*
X132639Y-134979D01*
X133239Y-135179D01*
X133839Y-135779D01*
G01X138639Y-130979D02*
Y-142979D01*
G01X137239Y-134979D02*
X140039D01*
G01X150039Y-142979D02*
Y-132779D01*
X150239Y-131779D01*
X150639Y-131179D01*
X151239Y-130979D01*
X151839Y-131379D01*
X152139Y-132379D01*
G01X150939Y-135779D02*
X148939D01*
G01X156639Y-142979D02*
X156039Y-142779D01*
X155439Y-141979D01*
X155039Y-140579D01*
X154839Y-138979D01*
X155039Y-137379D01*
X155439Y-135979D01*
X156039Y-135179D01*
X156639Y-134979D01*
X157239Y-135179D01*
X157839Y-135979D01*
X158239Y-137379D01*
X158339Y-138979D01*
X158239Y-140579D01*
X157839Y-141979D01*
X157239Y-142779D01*
X156639Y-142979D01*
G01X161239D02*
Y-134979D01*
G01Y-136579D02*
X161739Y-135779D01*
X162239Y-135179D01*
X162939Y-134979D01*
X163439Y-135179D01*
X164039Y-135779D01*
G01X172539Y-146579D02*
X173139Y-146979D01*
X173939Y-146579D01*
X174439Y-145779D01*
X174839Y-144779D01*
X175439Y-141579D01*
X176739Y-134979D01*
G01X173539D02*
X175439Y-141579D01*
G01X180639Y-142979D02*
X180039Y-142779D01*
X179439Y-141979D01*
X179039Y-140579D01*
X178839Y-138979D01*
X179039Y-137379D01*
X179439Y-135979D01*
X180039Y-135179D01*
X180639Y-134979D01*
X181239Y-135179D01*
X181839Y-135979D01*
X182239Y-137379D01*
X182339Y-138979D01*
X182239Y-140579D01*
X181839Y-141979D01*
X181239Y-142779D01*
X180639Y-142979D01*
G01X184939Y-134979D02*
Y-140579D01*
X185339Y-141979D01*
X185939Y-142779D01*
X186639Y-142979D01*
X187339Y-142779D01*
X187939Y-141979D01*
X188339Y-140579D01*
G01Y-142979D02*
Y-134979D01*
G01X197239Y-142979D02*
Y-134979D01*
G01Y-136579D02*
X197739Y-135779D01*
X198239Y-135179D01*
X198939Y-134979D01*
X199439Y-135179D01*
X200039Y-135779D01*
G01X203139Y-137579D02*
X206339D01*
X206039Y-136179D01*
X205539Y-135379D01*
X204839Y-134979D01*
X204139Y-135179D01*
X203539Y-135779D01*
X203139Y-137179D01*
X202939Y-138379D01*
Y-139579D01*
X203139Y-140779D01*
X203639Y-141979D01*
X204239Y-142779D01*
X204939Y-142979D01*
X205639Y-142579D01*
X206339Y-141379D01*
G01X210039Y-142979D02*
Y-132779D01*
X210239Y-131779D01*
X210639Y-131179D01*
X211239Y-130979D01*
X211839Y-131379D01*
X212139Y-132379D01*
G01X210939Y-135779D02*
X208939D01*
G01X215139Y-137579D02*
X218339D01*
X218039Y-136179D01*
X217539Y-135379D01*
X216839Y-134979D01*
X216139Y-135179D01*
X215539Y-135779D01*
X215139Y-137179D01*
X214939Y-138379D01*
Y-139579D01*
X215139Y-140779D01*
X215639Y-141979D01*
X216239Y-142779D01*
X216939Y-142979D01*
X217639Y-142579D01*
X218339Y-141379D01*
G01X221239Y-142979D02*
Y-134979D01*
G01Y-136579D02*
X221739Y-135779D01*
X222239Y-135179D01*
X222939Y-134979D01*
X223439Y-135179D01*
X224039Y-135779D01*
G01X227139Y-137579D02*
X230339D01*
X230039Y-136179D01*
X229539Y-135379D01*
X228839Y-134979D01*
X228139Y-135179D01*
X227539Y-135779D01*
X227139Y-137179D01*
X226939Y-138379D01*
Y-139579D01*
X227139Y-140779D01*
X227639Y-141979D01*
X228239Y-142779D01*
X228939Y-142979D01*
X229639Y-142579D01*
X230339Y-141379D01*
G01X232939Y-142979D02*
Y-134979D01*
G01Y-136979D02*
X233339Y-135979D01*
X233939Y-135179D01*
X234739Y-134979D01*
X235439Y-135179D01*
X236039Y-135979D01*
X236339Y-137379D01*
Y-142979D01*
G01X242239Y-135979D02*
X241539Y-135179D01*
X240939Y-134979D01*
X240139Y-135379D01*
X239539Y-136179D01*
X239139Y-137579D01*
X239039Y-138979D01*
X239139Y-140379D01*
X239539Y-141579D01*
X240139Y-142579D01*
X240939Y-142979D01*
X241639Y-142579D01*
X242239Y-141779D01*
G01X245139Y-137579D02*
X248339D01*
X248039Y-136179D01*
X247539Y-135379D01*
X246839Y-134979D01*
X246139Y-135179D01*
X245539Y-135779D01*
X245139Y-137179D01*
X244939Y-138379D01*
Y-139579D01*
X245139Y-140779D01*
X245639Y-141979D01*
X246239Y-142779D01*
X246939Y-142979D01*
X247639Y-142579D01*
X248339Y-141379D01*
G01X258639Y-130979D02*
Y-142979D01*
G01X257239Y-134979D02*
X260039D01*
G01X264639Y-142979D02*
X264039Y-142779D01*
X263439Y-141979D01*
X263039Y-140579D01*
X262839Y-138979D01*
X263039Y-137379D01*
X263439Y-135979D01*
X264039Y-135179D01*
X264639Y-134979D01*
X265239Y-135179D01*
X265839Y-135979D01*
X266239Y-137379D01*
X266339Y-138979D01*
X266239Y-140579D01*
X265839Y-141979D01*
X265239Y-142779D01*
X264639Y-142979D01*
G01X276039D02*
Y-132779D01*
X276239Y-131779D01*
X276639Y-131179D01*
X277239Y-130979D01*
X277839Y-131379D01*
X278139Y-132379D01*
G01X276939Y-135779D02*
X274939D01*
G01X282639Y-134979D02*
Y-142979D01*
G01Y-131779D02*
X282439Y-131579D01*
Y-131179D01*
X282639Y-130979D01*
X282839Y-131179D01*
Y-131579D01*
X282639Y-131779D01*
G01X286939Y-142979D02*
Y-134979D01*
G01Y-136979D02*
X287339Y-135979D01*
X287939Y-135179D01*
X288739Y-134979D01*
X289439Y-135179D01*
X290039Y-135979D01*
X290339Y-137379D01*
Y-142979D01*
G01X296439Y-130979D02*
Y-142979D01*
G01Y-141179D02*
X296039Y-142179D01*
X295439Y-142779D01*
X294739Y-142979D01*
X293939Y-142579D01*
X293339Y-141579D01*
X292939Y-140379D01*
X292839Y-138979D01*
X292939Y-137579D01*
X293339Y-136379D01*
X293939Y-135379D01*
X294739Y-134979D01*
X295439Y-135179D01*
X295939Y-135579D01*
X296439Y-136379D01*
G01X306639Y-130979D02*
Y-142979D01*
G01X305239Y-134979D02*
X308039D01*
G01X310939Y-142979D02*
Y-130979D01*
G01Y-136779D02*
X311439Y-135779D01*
X311939Y-135179D01*
X312739Y-134979D01*
X313339Y-135179D01*
X314039Y-135979D01*
X314339Y-137179D01*
Y-142979D01*
G01X317139Y-137579D02*
X320339D01*
X320039Y-136179D01*
X319539Y-135379D01*
X318839Y-134979D01*
X318139Y-135179D01*
X317539Y-135779D01*
X317139Y-137179D01*
X316939Y-138379D01*
Y-139579D01*
X317139Y-140779D01*
X317639Y-141979D01*
X318239Y-142779D01*
X318939Y-142979D01*
X319639Y-142579D01*
X320339Y-141379D01*
G01X332439Y-130979D02*
Y-142979D01*
G01Y-141179D02*
X332039Y-142179D01*
X331439Y-142779D01*
X330739Y-142979D01*
X329939Y-142579D01*
X329339Y-141579D01*
X328939Y-140379D01*
X328839Y-138979D01*
X328939Y-137579D01*
X329339Y-136379D01*
X329939Y-135379D01*
X330739Y-134979D01*
X331439Y-135179D01*
X331939Y-135579D01*
X332439Y-136379D01*
G01X336639Y-134979D02*
Y-142979D01*
G01Y-131779D02*
X336439Y-131579D01*
Y-131179D01*
X336639Y-130979D01*
X336839Y-131179D01*
Y-131579D01*
X336639Y-131779D01*
G01X342039Y-142979D02*
Y-132779D01*
X342239Y-131779D01*
X342639Y-131179D01*
X343239Y-130979D01*
X343839Y-131379D01*
X344139Y-132379D01*
G01X342939Y-135779D02*
X340939D01*
G01X348039Y-142979D02*
Y-132779D01*
X348239Y-131779D01*
X348639Y-131179D01*
X349239Y-130979D01*
X349839Y-131379D01*
X350139Y-132379D01*
G01X348939Y-135779D02*
X346939D01*
G01X353139Y-137579D02*
X356339D01*
X356039Y-136179D01*
X355539Y-135379D01*
X354839Y-134979D01*
X354139Y-135179D01*
X353539Y-135779D01*
X353139Y-137179D01*
X352939Y-138379D01*
Y-139579D01*
X353139Y-140779D01*
X353639Y-141979D01*
X354239Y-142779D01*
X354939Y-142979D01*
X355639Y-142579D01*
X356339Y-141379D01*
G01X359239Y-142979D02*
Y-134979D01*
G01Y-136579D02*
X359739Y-135779D01*
X360239Y-135179D01*
X360939Y-134979D01*
X361439Y-135179D01*
X362039Y-135779D01*
G01X365139Y-137579D02*
X368339D01*
X368039Y-136179D01*
X367539Y-135379D01*
X366839Y-134979D01*
X366139Y-135179D01*
X365539Y-135779D01*
X365139Y-137179D01*
X364939Y-138379D01*
Y-139579D01*
X365139Y-140779D01*
X365639Y-141979D01*
X366239Y-142779D01*
X366939Y-142979D01*
X367639Y-142579D01*
X368339Y-141379D01*
G01X370939Y-142979D02*
Y-134979D01*
G01Y-136979D02*
X371339Y-135979D01*
X371939Y-135179D01*
X372739Y-134979D01*
X373439Y-135179D01*
X374039Y-135979D01*
X374339Y-137379D01*
Y-142979D01*
G01X378639Y-130979D02*
Y-142979D01*
G01X377239Y-134979D02*
X380039D01*
G01X384639D02*
Y-142979D01*
G01Y-131779D02*
X384439Y-131579D01*
Y-131179D01*
X384639Y-130979D01*
X384839Y-131179D01*
Y-131579D01*
X384639Y-131779D01*
G01X392439Y-142979D02*
Y-134979D01*
G01Y-136379D02*
X392039Y-135579D01*
X391439Y-135179D01*
X390739Y-134979D01*
X390039Y-135379D01*
X389439Y-136179D01*
X389039Y-137379D01*
X388839Y-138979D01*
X389039Y-140579D01*
X389439Y-141779D01*
X390039Y-142579D01*
X390739Y-142979D01*
X391439Y-142779D01*
X392039Y-142179D01*
X392439Y-141379D01*
G01X396639Y-142979D02*
Y-130979D01*
G01X408639D02*
Y-142979D01*
G01X407239Y-134979D02*
X410039D01*
G01X413239Y-142979D02*
Y-134979D01*
G01Y-136579D02*
X413739Y-135779D01*
X414239Y-135179D01*
X414939Y-134979D01*
X415439Y-135179D01*
X416039Y-135779D01*
G01X422439Y-142979D02*
Y-134979D01*
G01Y-136379D02*
X422039Y-135579D01*
X421439Y-135179D01*
X420739Y-134979D01*
X420039Y-135379D01*
X419439Y-136179D01*
X419039Y-137379D01*
X418839Y-138979D01*
X419039Y-140579D01*
X419439Y-141779D01*
X420039Y-142579D01*
X420739Y-142979D01*
X421439Y-142779D01*
X422039Y-142179D01*
X422439Y-141379D01*
G01X428239Y-135979D02*
X427539Y-135179D01*
X426939Y-134979D01*
X426139Y-135379D01*
X425539Y-136179D01*
X425139Y-137579D01*
X425039Y-138979D01*
X425139Y-140379D01*
X425539Y-141579D01*
X426139Y-142579D01*
X426939Y-142979D01*
X427639Y-142579D01*
X428239Y-141779D01*
G01X431139Y-137579D02*
X434339D01*
X434039Y-136179D01*
X433539Y-135379D01*
X432839Y-134979D01*
X432139Y-135179D01*
X431539Y-135779D01*
X431139Y-137179D01*
X430939Y-138379D01*
Y-139579D01*
X431139Y-140779D01*
X431639Y-141979D01*
X432239Y-142779D01*
X432939Y-142979D01*
X433639Y-142579D01*
X434339Y-141379D01*
G01X437139Y-141579D02*
X437639Y-142379D01*
X438339Y-142979D01*
X438939D01*
X439539Y-142579D01*
X439939Y-141979D01*
X440139Y-141179D01*
X440039Y-139979D01*
X439639Y-139379D01*
X437839Y-138179D01*
X437439Y-136779D01*
X437639Y-135779D01*
X438039Y-135179D01*
X438639Y-134979D01*
X439239Y-135179D01*
X439839Y-135779D01*
G01X450639Y-134979D02*
Y-142979D01*
G01Y-131779D02*
X450439Y-131579D01*
Y-131179D01*
X450639Y-130979D01*
X450839Y-131179D01*
Y-131579D01*
X450639Y-131779D01*
G01X454939Y-142979D02*
Y-134979D01*
G01Y-136979D02*
X455339Y-135979D01*
X455939Y-135179D01*
X456739Y-134979D01*
X457439Y-135179D01*
X458039Y-135979D01*
X458339Y-137379D01*
Y-142979D01*
G01X468639D02*
Y-130979D01*
G01X476439Y-142979D02*
Y-134979D01*
G01Y-136379D02*
X476039Y-135579D01*
X475439Y-135179D01*
X474739Y-134979D01*
X474039Y-135379D01*
X473439Y-136179D01*
X473039Y-137379D01*
X472839Y-138979D01*
X473039Y-140579D01*
X473439Y-141779D01*
X474039Y-142579D01*
X474739Y-142979D01*
X475439Y-142779D01*
X476039Y-142179D01*
X476439Y-141379D01*
G01X478539Y-146579D02*
X479139Y-146979D01*
X479939Y-146579D01*
X480439Y-145779D01*
X480839Y-144779D01*
X481439Y-141579D01*
X482739Y-134979D01*
G01X479539D02*
X481439Y-141579D01*
G01X485139Y-137579D02*
X488339D01*
X488039Y-136179D01*
X487539Y-135379D01*
X486839Y-134979D01*
X486139Y-135179D01*
X485539Y-135779D01*
X485139Y-137179D01*
X484939Y-138379D01*
Y-139579D01*
X485139Y-140779D01*
X485639Y-141979D01*
X486239Y-142779D01*
X486939Y-142979D01*
X487639Y-142579D01*
X488339Y-141379D01*
G01X491239Y-142979D02*
Y-134979D01*
G01Y-136579D02*
X491739Y-135779D01*
X492239Y-135179D01*
X492939Y-134979D01*
X493439Y-135179D01*
X494039Y-135779D01*
G01X502639Y-130979D02*
Y-142979D01*
X506639D01*
G01X508439Y-140579D02*
X509039Y-141979D01*
X509839Y-142779D01*
X510739Y-142979D01*
X511539Y-142779D01*
X512339Y-141779D01*
X512839Y-140579D01*
X512939Y-139379D01*
X512739Y-137979D01*
X512039Y-136979D01*
X511339Y-136579D01*
X510439D01*
G01X511339D02*
X511939Y-135979D01*
X512439Y-134979D01*
X512639Y-133779D01*
X512439Y-132579D01*
X511939Y-131579D01*
X511039Y-130979D01*
X510139Y-131179D01*
X509239Y-131979D01*
G01X36516Y309567D02*
G02X22539I-6989J0D01*
G02X36516I6989J0D01*
G01Y1029528D02*
G02X22539I-6989J0D01*
G02X36516I6989J0D01*
G01X137795Y17717D02*
G02X122047I-7874J0D01*
G02X137795I7874J0D01*
G01X278642Y267717D02*
G02X264665I-6989J0D01*
G02X278642I6988J0D01*
G01Y673228D02*
G02X264665I-6989J0D01*
G02X278642I6988J0D01*
G01Y1078740D02*
G02X264665I-6989J0D01*
G02X278642I6988J0D01*
G01Y1484252D02*
G02X264665I-6989J0D01*
G02X278642I6988J0D01*
G01Y1889764D02*
G02X264665I-6989J0D01*
G02X278642I6988J0D01*
G01X1001083Y149606D02*
G02X987106I-6989J0D01*
G02X1001083I6988J0D01*
G01Y673228D02*
G02X987106I-6989J0D01*
G02X1001083I6988J0D01*
G01Y1068898D02*
G02X987106I-6989J0D01*
G02X1001083I6988J0D01*
G01X1001969Y1889764D02*
G02X986220I-7875J0D01*
G02X1001969I7874J0D01*
G01X1012008Y1416024D02*
G02X1026575I7284J0D01*
G02X1012008I-7283J0D01*
G01Y1694213D02*
G02X1026575I7284J0D01*
G02X1012008I-7283J0D01*
M02*
